FILE_TYPE = CONNECTIVITY;
{Allegro Design Entry HDL 16.6-p007 (v16-6-112F) 10/10/2012}
"PAGE_NUMBER" = 79;
0"NC";
1"M_H_DQS_DP<17:0>";
2"M_H_DQS_DN<17:0>";
3"M_H_DQ<63:0>";
4"M_H_MA<17:0>";
5"M_H_BA<1:0>";
6"M_H_BG<1:0>";
7"M_H_CLK_DP<3:0>";
8"M_H_CLK_DN<3:0>";
9"M_H_CS_N<7:0>";
10"M_H_CKE<3:0>";
11"M_H_ECC<7:0>";
12"M_H_ODT<3:0>";
13"PVDDQ_GHJ\g";
14"PVTT_GHJ\g";
15"GND\g";
16"GND\g";
17"GND\g";
18"PVPP_GHJ\g";
19"PVPP_GHJ\g";
20"P12V_NVDIMM_GHJ\g";
21"GND\g";
22"M_H_DQ<59>";
23"M_H_DQ<56>";
24"M_H_DQS_DP<1>";
25"TP_CH_H_DIMM_H0_RFU_2";
26"M_H_DQ<32>";
27"M_H_DQS_DN<15>";
28"M_H_DQ<52>";
29"M_H_VREF";
30"TP_CH_H_DIMM_H0_RFU_1";
31"TP_CH_H_DIMM_H0_RFU_0";
32"SMB_DDR_GHJ_VPP_SCL";
33"SMB_DDR_GHJ_VPP_SDA";
34"FM_ADR_COMPLETE_GHJ_N";
35"M_H_ACT_N";
36"M_H_ALERT_N";
37"M_H_ECC<1>";
38"M_H_ECC<0>";
39"M_H_PAR";
40"FM_DIMM_EVENT_COD_N";
41"M_GHJ_RST_N";
42"M_H_ECC<3>";
43"M_H_ECC<2>";
44"M_H_ECC<5>";
45"M_H_ECC<4>";
46"M_H_ECC<7>";
47"M_H_ODT<1>";
48"M_H_ODT<0>";
49"M_H_ECC<6>";
50"M_H_CLK_DN<0>";
51"M_H_CS_N<0>";
52"M_H_CKE<0>";
53"M_H_CKE<1>";
54"M_H_CS_N<1>";
55"M_H_C<2>";
56"M_H_CS_N<3>";
57"M_H_CS_N<2>";
58"M_H_CLK_DN<1>";
59"M_H_BG<0>";
60"M_H_CLK_DP<0>";
61"M_H_CLK_DP<1>";
62"M_H_BA<0>";
63"M_H_BG<1>";
64"M_H_MA<0>";
65"M_H_BA<1>";
66"M_H_DQ<5>";
67"M_H_DQ<2>";
68"M_H_DQ<3>";
69"M_H_DQ<16>";
70"M_H_DQ<14>";
71"M_H_DQ<27>";
72"M_H_DQ<26>";
73"M_H_DQ<39>";
74"M_H_DQ<37>";
75"M_H_DQ<34>";
76"M_H_DQ<1>";
77"M_H_DQ<0>";
78"M_H_DQ<7>";
79"M_H_DQ<8>";
80"M_H_DQ<10>";
81"M_H_DQ<13>";
82"M_H_DQ<12>";
83"M_H_DQ<15>";
84"M_H_DQ<17>";
85"M_H_DQ<19>";
86"M_H_DQ<21>";
87"M_H_DQ<20>";
88"M_H_DQ<23>";
89"M_H_DQ<22>";
90"M_H_DQ<25>";
91"M_H_DQ<24>";
92"M_H_DQ<31>";
93"M_H_DQ<30>";
94"M_H_DQ<33>";
95"M_H_DQ<35>";
96"M_H_DQ<36>";
97"M_H_DQ<38>";
98"M_H_DQ<41>";
99"M_H_DQ<40>";
100"M_H_DQ<43>";
101"M_H_DQ<42>";
102"M_H_DQ<45>";
103"M_H_DQ<44>";
104"M_H_DQ<47>";
105"M_H_DQ<29>";
106"M_H_DQ<28>";
107"M_H_DQ<4>";
108"M_H_DQ<6>";
109"M_H_DQ<11>";
110"M_H_DQ<9>";
111"M_H_DQ<18>";
112"M_H_MA<2>";
113"M_H_MA<6>";
114"M_H_MA<5>";
115"M_H_MA<4>";
116"M_H_MA<3>";
117"M_H_MA<1>";
118"M_H_MA<11>";
119"M_H_MA<10>";
120"M_H_MA<9>";
121"M_H_MA<8>";
122"M_H_MA<7>";
123"M_H_MA<16>";
124"M_H_MA<15>";
125"M_H_MA<14>";
126"M_H_MA<13>";
127"M_H_MA<12>";
128"M_H_MA<17>";
129"M_H_DQ<62>";
130"M_H_DQ<63>";
131"M_H_DQ<60>";
132"M_H_DQ<46>";
133"M_H_DQ<49>";
134"M_H_DQ<48>";
135"M_H_DQ<51>";
136"M_H_DQ<50>";
137"M_H_DQ<53>";
138"M_H_DQ<55>";
139"M_H_DQ<54>";
140"M_H_DQ<57>";
141"M_H_DQ<58>";
142"M_H_DQ<61>";
143"M_H_DQS_DP<6>";
144"M_H_DQS_DN<6>";
145"M_H_DQS_DP<5>";
146"M_H_DQS_DN<5>";
147"M_H_DQS_DP<4>";
148"M_H_DQS_DN<4>";
149"M_H_DQS_DP<3>";
150"M_H_DQS_DN<3>";
151"M_H_DQS_DP<2>";
152"M_H_DQS_DN<2>";
153"M_H_DQS_DN<1>";
154"M_H_DQS_DP<0>";
155"M_H_DQS_DN<0>";
156"M_H_DQS_DP<9>";
157"M_H_DQS_DN<9>";
158"M_H_DQS_DP<8>";
159"M_H_DQS_DN<8>";
160"M_H_DQS_DP<7>";
161"M_H_DQS_DN<7>";
162"M_H_DQS_DN<17>";
163"M_H_DQS_DP<16>";
164"M_H_DQS_DN<16>";
165"M_H_DQS_DP<15>";
166"M_H_DQS_DP<14>";
167"M_H_DQS_DN<14>";
168"M_H_DQS_DP<13>";
169"M_H_DQS_DN<13>";
170"M_H_DQS_DP<12>";
171"M_H_DQS_DN<12>";
172"M_H_DQS_DP<11>";
173"M_H_DQS_DN<11>";
174"M_H_DQS_DP<10>";
175"M_H_DQS_DN<10>";
176"M_H_DQS_DP<17>";
%"TAP"
"6","(650,4950)","2","mstr_standard","I10";
;
CDS_LIB"mstr_standard"
BODY_TYPE"PLUMBING"
HDL_TAP"TRUE";
"B \NAC \NWC"1;
"S \NAC"
BN"15"165;
%"TAP"
"6","(-1850,2000)","2","mstr_standard","I100";
;
CDS_LIB"mstr_standard"
BODY_TYPE"PLUMBING"
HDL_TAP"TRUE";
"B \NAC \NWC"3;
"S \NAC"
BN"4"107;
%"TAP"
"6","(-1850,2100)","2","mstr_standard","I101";
;
CDS_LIB"mstr_standard"
BODY_TYPE"PLUMBING"
HDL_TAP"TRUE";
"B \NAC \NWC"3;
"S \NAC"
BN"6"108;
%"TAP"
"6","(-1850,2050)","2","mstr_standard","I102";
;
CDS_LIB"mstr_standard"
BODY_TYPE"PLUMBING"
HDL_TAP"TRUE";
"B \NAC \NWC"3;
"S \NAC"
BN"7"78;
%"TAP"
"6","(-1850,2150)","2","mstr_standard","I103";
;
CDS_LIB"mstr_standard"
BODY_TYPE"PLUMBING"
HDL_TAP"TRUE";
"B \NAC \NWC"3;
"S \NAC"
BN"9"110;
%"TAP"
"6","(-1850,2200)","2","mstr_standard","I104";
;
CDS_LIB"mstr_standard"
BODY_TYPE"PLUMBING"
HDL_TAP"TRUE";
"B \NAC \NWC"3;
"S \NAC"
BN"8"79;
%"TAP"
"6","(-1850,2250)","2","mstr_standard","I105";
;
CDS_LIB"mstr_standard"
BODY_TYPE"PLUMBING"
HDL_TAP"TRUE";
"B \NAC \NWC"3;
"S \NAC"
BN"11"109;
%"TAP"
"6","(-1850,1900)","2","mstr_standard","I106";
;
CDS_LIB"mstr_standard"
BODY_TYPE"PLUMBING"
HDL_TAP"TRUE";
"B \NAC \NWC"3;
"S \NAC"
BN"2"67;
%"TAP"
"6","(-1850,1950)","2","mstr_standard","I107";
;
CDS_LIB"mstr_standard"
BODY_TYPE"PLUMBING"
HDL_TAP"TRUE";
"B \NAC \NWC"3;
"S \NAC"
BN"5"66;
%"TAP"
"6","(-1850,1800)","2","mstr_standard","I108";
;
CDS_LIB"mstr_standard"
BODY_TYPE"PLUMBING"
HDL_TAP"TRUE";
"B \NAC \NWC"3;
"S \NAC"
BN"0"77;
%"TAP"
"6","(-1850,1750)","2","mstr_standard","I109";
;
CDS_LIB"mstr_standard"
BODY_TYPE"PLUMBING"
HDL_TAP"TRUE";
"B \NAC \NWC"3;
"S \NAC"
BN"1"76;
%"TAP"
"6","(650,4850)","2","mstr_standard","I11";
;
CDS_LIB"mstr_standard"
BODY_TYPE"PLUMBING"
HDL_TAP"TRUE";
"B \NAC \NWC"1;
"S \NAC"
BN"14"166;
%"TAP"
"6","(-1850,1850)","2","mstr_standard","I110";
;
CDS_LIB"mstr_standard"
BODY_TYPE"PLUMBING"
HDL_TAP"TRUE";
"B \NAC \NWC"3;
"S \NAC"
BN"3"68;
%"SCONN288_H44441004"
"1","(-2600,3250)","0","mstr_sconn","I111";
;
CDS_SEC"1"
LOCATION"J1G2"
PART_NUMBER"H44441-004"
MATERIAL"SCONN"
PACK_TYPE"PIP"
BOM_COST"MEM"
CDS_LIB"mstr_sconn"
SEC_TYPE"PIP"
SEC"1"
CDS_LOCATION"J1G2"
ROOM"DDR4_CH_H";
"DQ<63>"
$PN"280"129;
"DQ<62>"
$PN"135"130;
"DQ<61>"
$PN"273"131;
"DQ<5>"
$PN"148"107;
"DQ<4>"
$PN"3"66;
"DQ<3>"
$PN"157"67;
"DQ<2>"
$PN"12"68;
"DQ<47>"
$PN"258"132;
"DQ<48>"
$PN"119"133;
"DQ<49>"
$PN"264"134;
"DQ<50>"
$PN"126"135;
"DQ<51>"
$PN"271"136;
"DQ<52>"
$PN"117"137;
"DQ<53>"
$PN"262"28;
"DQ<54>"
$PN"124"138;
"DQ<58>"
$PN"137"22;
"DQ<57>"
$PN"275"23;
"SAVE_N_NC"
$PN"230"34;
"RFU<1>"
$PN"227"30;
"RFU<0>"
$PN"205"31;
"DQ<17>"
$PN"172"69;
"DQ<15>"
$PN"166"70;
"DQ<26>"
$PN"45"71;
"DQ<27>"
$PN"190"72;
"S0_N"
$PN"84"51;
"CKE<0>"
$PN"60"52;
"ODT<1>"
$PN"91"47;
"ODT<0>"
$PN"87"48;
"CB<7>"
$PN"199"49;
"A16_RAS_N"
$PN"82"123;
"A15_CAS_N"
$PN"86"124;
"A14_WE_N"
$PN"228"125;
"A11"
$PN"210"118;
"A10"
$PN"225"119;
"DQ<38>"
$PN"102"73;
"DQ<36>"
$PN"95"74;
"DQ<35>"
$PN"249"75;
"A2"
$PN"216"112;
"ALERT_N"
$PN"208"36;
"ACT_N"
$PN"62"35;
"DQ<0>"
$PN"5"76;
"DQ<1>"
$PN"150"77;
"SA<1>"
$PN"140"19;
"SA<2>"
$PN"238"16;
"VDDSPD"
$PN"284"19;
"SA<0>"
$PN"139"16;
"BA<0>"
$PN"81"62;
"BG<1>"
$PN"207"63;
"BG<0>"
$PN"63"59;
"CK1P"
$PN"218"61;
"VREFCA"
$PN"146"29;
"SDA"
$PN"285"33;
"SCL"
$PN"141"32;
"RFU<2>"
$PN"144"25;
"RESET_N"
$PN"58"41;
"PAR"
$PN"222"39;
"EVENT_N"
$PN"78"40;
"DQ<6>"
$PN"10"78;
"DQ<7>"
$PN"155"108;
"DQ<8>"
$PN"16"110;
"DQ<9>"
$PN"161"79;
"DQ<10>"
$PN"23"109;
"DQ<11>"
$PN"168"80;
"DQ<12>"
$PN"14"81;
"DQ<13>"
$PN"159"82;
"DQ<14>"
$PN"21"83;
"DQ<16>"
$PN"27"84;
"DQ<18>"
$PN"34"85;
"DQ<19>"
$PN"179"111;
"DQ<20>"
$PN"25"86;
"DQ<21>"
$PN"170"87;
"DQ<22>"
$PN"32"88;
"DQ<23>"
$PN"177"89;
"DQ<24>"
$PN"38"90;
"DQ<25>"
$PN"183"91;
"DQ<30>"
$PN"43"92;
"DQ<31>"
$PN"188"93;
"DQ<32>"
$PN"97"94;
"DQ<33>"
$PN"242"26;
"DQ<34>"
$PN"104"95;
"DQ<37>"
$PN"240"96;
"DQ<39>"
$PN"247"97;
"DQ<40>"
$PN"108"98;
"DQ<41>"
$PN"253"99;
"DQ<42>"
$PN"115"100;
"DQ<43>"
$PN"260"101;
"DQ<44>"
$PN"106"102;
"DQ<45>"
$PN"251"103;
"DQ<46>"
$PN"113"104;
"DQ<55>"
$PN"269"139;
"DQ<56>"
$PN"130"140;
"DQ<59>"
$PN"282"141;
"DQ<60>"
$PN"128"142;
"CKE<1>"
$PN"203"53;
"CK0N"
$PN"75"50;
"CB<0>"
$PN"49"37;
"CB<1>"
$PN"194"38;
"CB<2>"
$PN"56"42;
"CB<3>"
$PN"201"43;
"CB<4>"
$PN"47"44;
"CB<5>"
$PN"192"45;
"CB<6>"
$PN"54"46;
"A9"
$PN"66"120;
"A8"
$PN"68"121;
"A7"
$PN"211"122;
"A6"
$PN"69"113;
"A5"
$PN"213"114;
"A4"
$PN"214"115;
"A3"
$PN"71"116;
"A17"
$PN"234"128;
"A13"
$PN"232"126;
"A12"
$PN"65"127;
"A1"
$PN"72"117;
"A0"
$PN"79"64;
"C<2>"
$PN"235"55;
"DQ<28>"
$PN"36"105;
"DQ<29>"
$PN"181"106;
"S1_N"
$PN"89"54;
"S2_N_C<0>"
$PN"93"57;
"S3_N_C<1>"
$PN"237"56;
"CK0P"
$PN"74"60;
"CK1N"
$PN"219"58;
"BA<1>"
$PN"224"65;
%"TAP"
"6","(-3350,4850)","0","mstr_standard","I112";
;
CDS_LIB"mstr_standard"
BODY_TYPE"PLUMBING"
HDL_TAP"TRUE";
"B \NAC \NWC"4;
"S \NAC"
BN"16"123;
%"TAP"
"6","(-3350,4900)","0","mstr_standard","I113";
;
CDS_LIB"mstr_standard"
BODY_TYPE"PLUMBING"
HDL_TAP"TRUE";
"B \NAC \NWC"4;
"S \NAC"
BN"17"128;
%"TAP"
"6","(-3350,4800)","0","mstr_standard","I114";
;
CDS_LIB"mstr_standard"
BODY_TYPE"PLUMBING"
HDL_TAP"TRUE";
"B \NAC \NWC"4;
"S \NAC"
BN"15"124;
%"TAP"
"6","(-3350,4750)","0","mstr_standard","I115";
;
CDS_LIB"mstr_standard"
BODY_TYPE"PLUMBING"
HDL_TAP"TRUE";
"B \NAC \NWC"4;
"S \NAC"
BN"14"125;
%"TAP"
"6","(-3350,4700)","0","mstr_standard","I116";
;
CDS_LIB"mstr_standard"
BODY_TYPE"PLUMBING"
HDL_TAP"TRUE";
"B \NAC \NWC"4;
"S \NAC"
BN"13"126;
%"TAP"
"6","(-3350,4600)","0","mstr_standard","I117";
;
CDS_LIB"mstr_standard"
BODY_TYPE"PLUMBING"
HDL_TAP"TRUE";
"B \NAC \NWC"4;
"S \NAC"
BN"11"118;
%"TAP"
"6","(-3350,4650)","0","mstr_standard","I118";
;
CDS_LIB"mstr_standard"
BODY_TYPE"PLUMBING"
HDL_TAP"TRUE";
"B \NAC \NWC"4;
"S \NAC"
BN"12"127;
%"TAP"
"6","(-3350,4550)","0","mstr_standard","I119";
;
CDS_LIB"mstr_standard"
BODY_TYPE"PLUMBING"
HDL_TAP"TRUE";
"B \NAC \NWC"4;
"S \NAC"
BN"10"119;
%"TAP"
"6","(650,4750)","2","mstr_standard","I12";
;
CDS_LIB"mstr_standard"
BODY_TYPE"PLUMBING"
HDL_TAP"TRUE";
"B \NAC \NWC"1;
"S \NAC"
BN"13"168;
%"TAP"
"6","(-3350,4500)","0","mstr_standard","I120";
;
CDS_LIB"mstr_standard"
BODY_TYPE"PLUMBING"
HDL_TAP"TRUE";
"B \NAC \NWC"4;
"S \NAC"
BN"9"120;
%"TAP"
"6","(-3350,4450)","0","mstr_standard","I121";
;
CDS_LIB"mstr_standard"
BODY_TYPE"PLUMBING"
HDL_TAP"TRUE";
"B \NAC \NWC"4;
"S \NAC"
BN"8"121;
%"TAP"
"6","(-3350,4350)","0","mstr_standard","I122";
;
CDS_LIB"mstr_standard"
BODY_TYPE"PLUMBING"
HDL_TAP"TRUE";
"B \NAC \NWC"4;
"S \NAC"
BN"6"113;
%"TAP"
"6","(-3350,4400)","0","mstr_standard","I123";
;
CDS_LIB"mstr_standard"
BODY_TYPE"PLUMBING"
HDL_TAP"TRUE";
"B \NAC \NWC"4;
"S \NAC"
BN"7"122;
%"TAP"
"6","(-3350,4300)","0","mstr_standard","I124";
;
CDS_LIB"mstr_standard"
BODY_TYPE"PLUMBING"
HDL_TAP"TRUE";
"B \NAC \NWC"4;
"S \NAC"
BN"5"114;
%"TAP"
"6","(-3350,4200)","0","mstr_standard","I125";
;
CDS_LIB"mstr_standard"
BODY_TYPE"PLUMBING"
HDL_TAP"TRUE";
"B \NAC \NWC"4;
"S \NAC"
BN"3"116;
%"TAP"
"6","(-3350,4250)","0","mstr_standard","I126";
;
CDS_LIB"mstr_standard"
BODY_TYPE"PLUMBING"
HDL_TAP"TRUE";
"B \NAC \NWC"4;
"S \NAC"
BN"4"115;
%"TAP"
"6","(-3350,4150)","0","mstr_standard","I127";
;
CDS_LIB"mstr_standard"
BODY_TYPE"PLUMBING"
HDL_TAP"TRUE";
"B \NAC \NWC"4;
"S \NAC"
BN"2"112;
%"TAP"
"6","(-3350,4050)","0","mstr_standard","I128";
;
CDS_LIB"mstr_standard"
BODY_TYPE"PLUMBING"
HDL_TAP"TRUE";
"B \NAC \NWC"4;
"S \NAC"
BN"0"64;
%"TAP"
"6","(-3350,4100)","0","mstr_standard","I129";
;
CDS_LIB"mstr_standard"
BODY_TYPE"PLUMBING"
HDL_TAP"TRUE";
"B \NAC \NWC"4;
"S \NAC"
BN"1"117;
%"TAP"
"6","(650,4650)","2","mstr_standard","I13";
;
CDS_LIB"mstr_standard"
BODY_TYPE"PLUMBING"
HDL_TAP"TRUE";
"B \NAC \NWC"1;
"S \NAC"
BN"12"170;
%"TAP"
"6","(-3350,3950)","0","mstr_standard","I131";
;
CDS_LIB"mstr_standard"
BODY_TYPE"PLUMBING"
HDL_TAP"TRUE";
"B \NAC \NWC"5;
"S \NAC"
BN"1"65;
%"TAP"
"6","(-3350,3900)","0","mstr_standard","I132";
;
CDS_LIB"mstr_standard"
BODY_TYPE"PLUMBING"
HDL_TAP"TRUE";
"B \NAC \NWC"5;
"S \NAC"
BN"0"62;
%"TAP"
"6","(-3350,3800)","0","mstr_standard","I133";
;
CDS_LIB"mstr_standard"
BODY_TYPE"PLUMBING"
HDL_TAP"TRUE";
"B \NAC \NWC"6;
"S \NAC"
BN"0"59;
%"TAP"
"6","(-3350,3850)","0","mstr_standard","I134";
;
CDS_LIB"mstr_standard"
BODY_TYPE"PLUMBING"
HDL_TAP"TRUE";
"B \NAC \NWC"6;
"S \NAC"
BN"1"63;
%"TAP"
"6","(-3350,2800)","0","mstr_standard","I138";
;
CDS_LIB"mstr_standard"
BODY_TYPE"PLUMBING"
HDL_TAP"TRUE";
"B \NAC \NWC"11;
"S \NAC"
BN"7"46;
%"TAP"
"6","(-3350,2850)","0","mstr_standard","I139";
;
CDS_LIB"mstr_standard"
BODY_TYPE"PLUMBING"
HDL_TAP"TRUE";
"B \NAC \NWC"11;
"S \NAC"
BN"6"49;
%"PVDDQ_GHJ"
"1","(-1525,2525)","0","mstr_symbols","I14";
;
VOLTAGE"1.2V"
BOM_COST"MEM"
CDS_LIB"mstr_symbols"
BODY_TYPE"PLUMBING"
ROOM"DDR4_CH_H"
HDL_POWER"PVDDQ_GHJ";
"G\NAC"13;
%"TAP"
"6","(-3350,2750)","0","mstr_standard","I140";
;
CDS_LIB"mstr_standard"
BODY_TYPE"PLUMBING"
HDL_TAP"TRUE";
"B \NAC \NWC"11;
"S \NAC"
BN"4"45;
%"TAP"
"6","(-3350,2700)","0","mstr_standard","I141";
;
CDS_LIB"mstr_standard"
BODY_TYPE"PLUMBING"
HDL_TAP"TRUE";
"B \NAC \NWC"11;
"S \NAC"
BN"5"44;
%"TAP"
"6","(-3350,2650)","0","mstr_standard","I142";
;
CDS_LIB"mstr_standard"
BODY_TYPE"PLUMBING"
HDL_TAP"TRUE";
"B \NAC \NWC"11;
"S \NAC"
BN"2"43;
%"TAP"
"6","(-3350,2550)","0","mstr_standard","I143";
;
CDS_LIB"mstr_standard"
BODY_TYPE"PLUMBING"
HDL_TAP"TRUE";
"B \NAC \NWC"11;
"S \NAC"
BN"0"38;
%"TAP"
"6","(-3350,2600)","0","mstr_standard","I144";
;
CDS_LIB"mstr_standard"
BODY_TYPE"PLUMBING"
HDL_TAP"TRUE";
"B \NAC \NWC"11;
"S \NAC"
BN"3"42;
%"TAP"
"6","(-3350,2500)","0","mstr_standard","I145";
;
CDS_LIB"mstr_standard"
BODY_TYPE"PLUMBING"
HDL_TAP"TRUE";
"B \NAC \NWC"11;
"S \NAC"
BN"1"37;
%"TAP"
"6","(-3350,3700)","0","mstr_standard","I152";
;
CDS_LIB"mstr_standard"
BODY_TYPE"PLUMBING"
HDL_TAP"TRUE";
"B \NAC \NWC"7;
"S \NAC"
BN"1"61;
%"TAP"
"6","(-3350,3600)","0","mstr_standard","I153";
;
CDS_LIB"mstr_standard"
BODY_TYPE"PLUMBING"
HDL_TAP"TRUE";
"B \NAC \NWC"7;
"S \NAC"
BN"0"60;
%"TAP"
"6","(-3550,3650)","0","mstr_standard","I154";
;
CDS_LIB"mstr_standard"
BODY_TYPE"PLUMBING"
HDL_TAP"TRUE";
"B \NAC \NWC"8;
"S \NAC"
BN"1"58;
%"TAP"
"6","(-3550,3550)","0","mstr_standard","I155";
;
CDS_LIB"mstr_standard"
BODY_TYPE"PLUMBING"
HDL_TAP"TRUE";
"B \NAC \NWC"8;
"S \NAC"
BN"0"50;
%"TAP"
"6","(-3350,3400)","0","mstr_standard","I158";
;
CDS_LIB"mstr_standard"
BODY_TYPE"PLUMBING"
HDL_TAP"TRUE";
"B \NAC \NWC"9;
"S \NAC"
BN"3"56;
%"TAP"
"6","(-3350,3350)","0","mstr_standard","I159";
;
CDS_LIB"mstr_standard"
BODY_TYPE"PLUMBING"
HDL_TAP"TRUE";
"B \NAC \NWC"9;
"S \NAC"
BN"2"57;
%"PVTT_GHJ"
"1","(-1300,2700)","0","mstr_symbols","I16";
;
VOLTAGE"0.6V"
BOM_COST"MEM"
CDS_LIB"mstr_symbols"
BODY_TYPE"PLUMBING"
ROOM"DDR4_CH_H"
HDL_POWER"PVTT_GHJ";
"G\NAC"14;
%"TAP"
"6","(-3350,3300)","0","mstr_standard","I160";
;
CDS_LIB"mstr_standard"
BODY_TYPE"PLUMBING"
HDL_TAP"TRUE";
"B \NAC \NWC"9;
"S \NAC"
BN"1"54;
%"TAP"
"6","(-3350,3250)","0","mstr_standard","I161";
;
CDS_LIB"mstr_standard"
BODY_TYPE"PLUMBING"
HDL_TAP"TRUE";
"B \NAC \NWC"9;
"S \NAC"
BN"0"51;
%"TAP"
"6","(-3350,3150)","0","mstr_standard","I162";
;
CDS_LIB"mstr_standard"
BODY_TYPE"PLUMBING"
HDL_TAP"TRUE";
"B \NAC \NWC"10;
"S \NAC"
BN"1"53;
%"TAP"
"6","(-3350,3100)","0","mstr_standard","I163";
;
CDS_LIB"mstr_standard"
BODY_TYPE"PLUMBING"
HDL_TAP"TRUE";
"B \NAC \NWC"10;
"S \NAC"
BN"0"52;
%"TAP"
"6","(-3350,3000)","0","mstr_standard","I164";
;
CDS_LIB"mstr_standard"
BODY_TYPE"PLUMBING"
HDL_TAP"TRUE";
"B \NAC \NWC"12;
"S \NAC"
BN"1"47;
%"TAP"
"6","(-3350,2950)","0","mstr_standard","I168";
;
CDS_LIB"mstr_standard"
BODY_TYPE"PLUMBING"
HDL_TAP"TRUE";
"B \NAC \NWC"12;
"S \NAC"
BN"0"48;
%"SCONN288_H44441004"
"4","(-450,2000)","0","mstr_sconn","I169";
;
CDS_SEC"4"
PART_NUMBER"H44441-004"
LOCATION"J1G2"
MATERIAL"SCONN"
PACK_TYPE"PIP"
BOM_COST"MEM"
CDS_LIB"mstr_sconn"
SEC_TYPE"PIP"
SEC"4"
CDS_LOCATION"J1G2"
ROOM"DDR4_CH_H";
"VPP<4>"
$PN"142"18;
"VTT<1>"
$PN"77"14;
"VPP<0>"
$PN"287"18;
"VPP<1>"
$PN"286"18;
"VPP<2>"
$PN"288"18;
"VPP<3>"
$PN"143"18;
"VDD<1>"
$PN"233"13;
"VDD<2>"
$PN"231"13;
"VDD<3>"
$PN"229"13;
"VDD<4>"
$PN"226"13;
"VDD<5>"
$PN"223"13;
"VDD<7>"
$PN"217"13;
"VDD<8>"
$PN"215"13;
"VDD<9>"
$PN"212"13;
"VDD<11>"
$PN"206"13;
"VDD<12>"
$PN"204"13;
"VDD<14>"
$PN"90"13;
"VDD<15>"
$PN"88"13;
"VDD<17>"
$PN"83"13;
"VDD<18>"
$PN"80"13;
"VDD<20>"
$PN"73"13;
"VDD<21>"
$PN"70"13;
"VDD<22>"
$PN"67"13;
"VDD<24>"
$PN"61"13;
"12V<0>"
$PN"145"20;
"12V<1>"
$PN"1"20;
"VTT<0>"
$PN"221"14;
"VDD<25>"
$PN"59"13;
"VDD<23>"
$PN"64"13;
"VDD<19>"
$PN"76"13;
"VDD<16>"
$PN"85"13;
"VDD<13>"
$PN"92"13;
"VDD<10>"
$PN"209"13;
"VDD<6>"
$PN"220"13;
"VDD<0>"
$PN"236"13;
%"TAP"
"6","(850,4600)","2","mstr_standard","I17";
;
CDS_LIB"mstr_standard"
BODY_TYPE"PLUMBING"
HDL_TAP"TRUE";
"B \NAC \NWC"2;
"S \NAC"
BN"12"171;
%"GND"
"1","(2450,1100)","2","mstr_symbols","I170";
;
VOLTAGE"0"
CDS_LIB"mstr_symbols"
SIZE"1B"
BOM_COST"MEM"
BODY_TYPE"PLUMBING"
ROOM"DDR4_CH_H"
HDL_POWER"GND";
"A\NAC"15;
%"GND"
"1","(-5200,1900)","2","mstr_symbols","I175";
;
VOLTAGE"0"
CDS_LIB"mstr_symbols"
SIZE"1B"
BOM_COST"MEM"
BODY_TYPE"PLUMBING"
ROOM"DDR4_CH_H"
HDL_POWER"GND";
"A\NAC"16;
%"GND"
"1","(-4600,1300)","0","mstr_symbols","I177";
;
VOLTAGE"0"
BOM_COST"MEM"
SIZE"1B"
CDS_LIB"mstr_symbols"
BODY_TYPE"PLUMBING"
ROOM"DDR4_CH_H"
HDL_POWER"GND";
"A\NAC"17;
%"CAP_A"
"1","(-4600,1550)","2","dev_discrete","I178";
;
LOCATION"C9U7"
PART_NUMBER"A36096-045"
VALUE"0.01UF"
TOLERANCE"10%"
PACK_TYPE"0402V"
VOLTAGE"25V"
MATERIAL"X7R"
CDS_LOCATION"C9U7"
BOM_COST"MEM"
CDS_LIB"dev_discrete"
CDS_SEC"1"
$SEC"1"
ROOM"DDR4_CH_J";
"B"
$PN"2"17;
"A"
$PN"1"29;
%"PVPP_GHJ"
"1","(-1150,3000)","0","mstr_symbols","I179";
;
VOLTAGE"2.5V"
BOM_COST"MEM"
CDS_LIB"mstr_symbols"
BODY_TYPE"PLUMBING"
ROOM"DDR4_CH_H"
HDL_POWER"PVPP_GHJ";
"G\NAC"18;
%"TAP"
"6","(850,4500)","2","mstr_standard","I18";
;
CDS_LIB"mstr_standard"
BODY_TYPE"PLUMBING"
HDL_TAP"TRUE";
"B \NAC \NWC"2;
"S \NAC"
BN"11"173;
%"PVPP_GHJ"
"1","(-5200,2250)","0","mstr_symbols","I180";
;
VOLTAGE"2.5V"
BOM_COST"MEM"
CDS_LIB"mstr_symbols"
BODY_TYPE"PLUMBING"
ROOM"DDR4_CH_H"
HDL_POWER"PVPP_GHJ";
"G\NAC"19;
%"TAP"
"6","(650,3450)","2","mstr_standard","I185";
;
CDS_LIB"mstr_standard"
BODY_TYPE"PLUMBING"
HDL_TAP"TRUE";
"B \NAC \NWC"1;
"S \NAC"
BN"0"154;
%"P12V_NVDIMM_GHJ"
"1","(250,2975)","0","mstr_symbols","I186";
;
VOLTAGE"12.0"
CDS_LIB"mstr_symbols"
BODY_TYPE"PLUMBING"
HDL_POWER"P12V_NVDIMM_GHJ";
"G\NAC"20;
%"TAP"
"6","(850,4400)","2","mstr_standard","I19";
;
CDS_LIB"mstr_standard"
BODY_TYPE"PLUMBING"
HDL_TAP"TRUE";
"B \NAC \NWC"2;
"S \NAC"
BN"10"175;
%"TAP"
"6","(850,4200)","2","mstr_standard","I20";
;
CDS_LIB"mstr_standard"
BODY_TYPE"PLUMBING"
HDL_TAP"TRUE";
"B \NAC \NWC"2;
"S \NAC"
BN"8"159;
%"TAP"
"6","(850,4300)","2","mstr_standard","I21";
;
CDS_LIB"mstr_standard"
BODY_TYPE"PLUMBING"
HDL_TAP"TRUE";
"B \NAC \NWC"2;
"S \NAC"
BN"9"157;
%"TAP"
"6","(650,4550)","2","mstr_standard","I22";
;
CDS_LIB"mstr_standard"
BODY_TYPE"PLUMBING"
HDL_TAP"TRUE";
"B \NAC \NWC"1;
"S \NAC"
BN"11"172;
%"TAP"
"6","(650,4450)","2","mstr_standard","I23";
;
CDS_LIB"mstr_standard"
BODY_TYPE"PLUMBING"
HDL_TAP"TRUE";
"B \NAC \NWC"1;
"S \NAC"
BN"10"174;
%"TAP"
"6","(650,4350)","2","mstr_standard","I24";
;
CDS_LIB"mstr_standard"
BODY_TYPE"PLUMBING"
HDL_TAP"TRUE";
"B \NAC \NWC"1;
"S \NAC"
BN"9"156;
%"TAP"
"6","(650,4250)","2","mstr_standard","I25";
;
CDS_LIB"mstr_standard"
BODY_TYPE"PLUMBING"
HDL_TAP"TRUE";
"B \NAC \NWC"1;
"S \NAC"
BN"8"158;
%"TAP"
"6","(650,4150)","2","mstr_standard","I26";
;
CDS_LIB"mstr_standard"
BODY_TYPE"PLUMBING"
HDL_TAP"TRUE";
"B \NAC \NWC"1;
"S \NAC"
BN"7"160;
%"TAP"
"6","(850,4100)","2","mstr_standard","I27";
;
CDS_LIB"mstr_standard"
BODY_TYPE"PLUMBING"
HDL_TAP"TRUE";
"B \NAC \NWC"2;
"S \NAC"
BN"7"161;
%"TAP"
"6","(850,4000)","2","mstr_standard","I28";
;
CDS_LIB"mstr_standard"
BODY_TYPE"PLUMBING"
HDL_TAP"TRUE";
"B \NAC \NWC"2;
"S \NAC"
BN"6"144;
%"TAP"
"6","(850,3900)","2","mstr_standard","I29";
;
CDS_LIB"mstr_standard"
BODY_TYPE"PLUMBING"
HDL_TAP"TRUE";
"B \NAC \NWC"2;
"S \NAC"
BN"5"146;
%"TAP"
"6","(850,5100)","2","mstr_standard","I3";
;
CDS_LIB"mstr_standard"
BODY_TYPE"PLUMBING"
HDL_TAP"TRUE";
"B \NAC \NWC"2;
"S \NAC"
BN"17"162;
%"TAP"
"6","(850,3700)","2","mstr_standard","I30";
;
CDS_LIB"mstr_standard"
BODY_TYPE"PLUMBING"
HDL_TAP"TRUE";
"B \NAC \NWC"2;
"S \NAC"
BN"3"150;
%"TAP"
"6","(850,3800)","2","mstr_standard","I31";
;
CDS_LIB"mstr_standard"
BODY_TYPE"PLUMBING"
HDL_TAP"TRUE";
"B \NAC \NWC"2;
"S \NAC"
BN"4"148;
%"TAP"
"6","(650,4050)","2","mstr_standard","I32";
;
CDS_LIB"mstr_standard"
BODY_TYPE"PLUMBING"
HDL_TAP"TRUE";
"B \NAC \NWC"1;
"S \NAC"
BN"6"143;
%"TAP"
"6","(650,3950)","2","mstr_standard","I33";
;
CDS_LIB"mstr_standard"
BODY_TYPE"PLUMBING"
HDL_TAP"TRUE";
"B \NAC \NWC"1;
"S \NAC"
BN"5"145;
%"TAP"
"6","(650,3850)","2","mstr_standard","I34";
;
CDS_LIB"mstr_standard"
BODY_TYPE"PLUMBING"
HDL_TAP"TRUE";
"B \NAC \NWC"1;
"S \NAC"
BN"4"147;
%"TAP"
"6","(650,3750)","2","mstr_standard","I35";
;
CDS_LIB"mstr_standard"
BODY_TYPE"PLUMBING"
HDL_TAP"TRUE";
"B \NAC \NWC"1;
"S \NAC"
BN"3"149;
%"TAP"
"6","(650,3650)","2","mstr_standard","I36";
;
CDS_LIB"mstr_standard"
BODY_TYPE"PLUMBING"
HDL_TAP"TRUE";
"B \NAC \NWC"1;
"S \NAC"
BN"2"151;
%"TAP"
"6","(850,3500)","2","mstr_standard","I37";
;
CDS_LIB"mstr_standard"
BODY_TYPE"PLUMBING"
HDL_TAP"TRUE";
"B \NAC \NWC"2;
"S \NAC"
BN"1"153;
%"TAP"
"6","(850,3600)","2","mstr_standard","I38";
;
CDS_LIB"mstr_standard"
BODY_TYPE"PLUMBING"
HDL_TAP"TRUE";
"B \NAC \NWC"2;
"S \NAC"
BN"2"152;
%"TAP"
"6","(850,3400)","2","mstr_standard","I39";
;
CDS_LIB"mstr_standard"
BODY_TYPE"PLUMBING"
HDL_TAP"TRUE";
"B \NAC \NWC"2;
"S \NAC"
BN"0"155;
%"TAP"
"6","(850,5000)","2","mstr_standard","I4";
;
CDS_LIB"mstr_standard"
BODY_TYPE"PLUMBING"
HDL_TAP"TRUE";
"B \NAC \NWC"2;
"S \NAC"
BN"16"164;
%"TAP"
"6","(650,3550)","2","mstr_standard","I40";
;
CDS_LIB"mstr_standard"
BODY_TYPE"PLUMBING"
HDL_TAP"TRUE";
"B \NAC \NWC"1;
"S \NAC"
BN"1"24;
%"SCONN288_H44441004"
"3","(1750,2400)","0","mstr_sconn","I43";
;
CDS_SEC"3"
LOCATION"J1G2"
PART_NUMBER"H44441-004"
MATERIAL"SCONN"
PACK_TYPE"PIP"
BOM_COST"MEM"
CDS_LIB"mstr_sconn"
SEC_TYPE"PIP"
SEC"3"
CDS_LOCATION"J1G2"
ROOM"DDR4_CH_H";
"VSS<93>"
$PN"2"21;
"VSS<92>"
$PN"4"21;
"VSS<91>"
$PN"6"21;
"VSS<90>"
$PN"9"21;
"VSS<89>"
$PN"11"21;
"VSS<88>"
$PN"13"21;
"VSS<0>"
$PN"283"15;
"VSS<1>"
$PN"281"15;
"VSS<2>"
$PN"279"15;
"VSS<3>"
$PN"276"15;
"VSS<4>"
$PN"274"15;
"VSS<5>"
$PN"272"15;
"VSS<6>"
$PN"270"15;
"VSS<7>"
$PN"268"15;
"VSS<8>"
$PN"265"15;
"VSS<9>"
$PN"263"15;
"VSS<10>"
$PN"261"15;
"VSS<11>"
$PN"259"15;
"VSS<12>"
$PN"257"15;
"VSS<13>"
$PN"254"15;
"VSS<14>"
$PN"252"15;
"VSS<15>"
$PN"250"15;
"VSS<16>"
$PN"248"15;
"VSS<17>"
$PN"246"15;
"VSS<18>"
$PN"243"15;
"VSS<19>"
$PN"241"15;
"VSS<20>"
$PN"239"15;
"VSS<21>"
$PN"202"15;
"VSS<22>"
$PN"200"15;
"VSS<23>"
$PN"198"15;
"VSS<24>"
$PN"195"15;
"VSS<25>"
$PN"193"15;
"VSS<26>"
$PN"191"15;
"VSS<27>"
$PN"189"15;
"VSS<28>"
$PN"187"15;
"VSS<29>"
$PN"184"15;
"VSS<30>"
$PN"182"15;
"VSS<31>"
$PN"180"15;
"VSS<32>"
$PN"178"15;
"VSS<33>"
$PN"176"15;
"VSS<34>"
$PN"173"15;
"VSS<35>"
$PN"171"15;
"VSS<36>"
$PN"169"15;
"VSS<37>"
$PN"167"15;
"VSS<38>"
$PN"165"15;
"VSS<39>"
$PN"162"15;
"VSS<40>"
$PN"160"15;
"VSS<41>"
$PN"158"15;
"VSS<42>"
$PN"156"15;
"VSS<43>"
$PN"154"15;
"VSS<44>"
$PN"151"15;
"VSS<47>"
$PN"138"21;
"VSS<48>"
$PN"136"21;
"VSS<49>"
$PN"134"21;
"VSS<50>"
$PN"131"21;
"VSS<51>"
$PN"129"21;
"VSS<52>"
$PN"127"21;
"VSS<53>"
$PN"125"21;
"VSS<54>"
$PN"123"21;
"VSS<55>"
$PN"120"21;
"VSS<56>"
$PN"118"21;
"VSS<57>"
$PN"116"21;
"VSS<58>"
$PN"114"21;
"VSS<59>"
$PN"112"21;
"VSS<60>"
$PN"109"21;
"VSS<61>"
$PN"107"21;
"VSS<62>"
$PN"105"21;
"VSS<63>"
$PN"103"21;
"VSS<64>"
$PN"101"21;
"VSS<65>"
$PN"98"21;
"VSS<66>"
$PN"96"21;
"VSS<67>"
$PN"94"21;
"VSS<68>"
$PN"57"21;
"VSS<69>"
$PN"55"21;
"VSS<70>"
$PN"53"21;
"VSS<71>"
$PN"50"21;
"VSS<72>"
$PN"48"21;
"VSS<73>"
$PN"46"21;
"VSS<74>"
$PN"44"21;
"VSS<75>"
$PN"42"21;
"VSS<76>"
$PN"39"21;
"VSS<77>"
$PN"37"21;
"VSS<78>"
$PN"35"21;
"VSS<79>"
$PN"33"21;
"VSS<80>"
$PN"31"21;
"VSS<81>"
$PN"28"21;
"VSS<82>"
$PN"26"21;
"VSS<83>"
$PN"24"21;
"VSS<84>"
$PN"22"21;
"VSS<85>"
$PN"20"21;
"VSS<86>"
$PN"17"21;
"VSS<87>"
$PN"15"21;
"VSS<45>"
$PN"149"15;
"VSS<46>"
$PN"147"15;
%"GND"
"1","(1050,1100)","2","mstr_symbols","I44";
;
VOLTAGE"0"
CDS_LIB"mstr_symbols"
SIZE"1B"
BOM_COST"MEM"
BODY_TYPE"PLUMBING"
ROOM"DDR4_CH_H"
HDL_POWER"GND";
"A\NAC"21;
%"TAP"
"6","(-1850,4850)","2","mstr_standard","I46";
;
CDS_LIB"mstr_standard"
BODY_TYPE"PLUMBING"
HDL_TAP"TRUE";
"B \NAC \NWC"3;
"S \NAC"
BN"63"130;
%"TAP"
"6","(-1850,4900)","2","mstr_standard","I47";
;
CDS_LIB"mstr_standard"
BODY_TYPE"PLUMBING"
HDL_TAP"TRUE";
"B \NAC \NWC"3;
"S \NAC"
BN"62"129;
%"TAP"
"6","(-1850,4750)","2","mstr_standard","I48";
;
CDS_LIB"mstr_standard"
BODY_TYPE"PLUMBING"
HDL_TAP"TRUE";
"B \NAC \NWC"3;
"S \NAC"
BN"61"142;
%"TAP"
"6","(-1850,4800)","2","mstr_standard","I49";
;
CDS_LIB"mstr_standard"
BODY_TYPE"PLUMBING"
HDL_TAP"TRUE";
"B \NAC \NWC"3;
"S \NAC"
BN"60"131;
%"TAP"
"6","(850,4900)","2","mstr_standard","I5";
;
CDS_LIB"mstr_standard"
BODY_TYPE"PLUMBING"
HDL_TAP"TRUE";
"B \NAC \NWC"2;
"S \NAC"
BN"15"27;
%"TAP"
"6","(-1850,4700)","2","mstr_standard","I50";
;
CDS_LIB"mstr_standard"
BODY_TYPE"PLUMBING"
HDL_TAP"TRUE";
"B \NAC \NWC"3;
"S \NAC"
BN"58"141;
%"TAP"
"6","(-1850,4650)","2","mstr_standard","I51";
;
CDS_LIB"mstr_standard"
BODY_TYPE"PLUMBING"
HDL_TAP"TRUE";
"B \NAC \NWC"3;
"S \NAC"
BN"59"22;
%"TAP"
"6","(-1850,4600)","2","mstr_standard","I52";
;
CDS_LIB"mstr_standard"
BODY_TYPE"PLUMBING"
HDL_TAP"TRUE";
"B \NAC \NWC"3;
"S \NAC"
BN"56"23;
%"TAP"
"6","(-1850,4400)","2","mstr_standard","I53";
;
CDS_LIB"mstr_standard"
BODY_TYPE"PLUMBING"
HDL_TAP"TRUE";
"B \NAC \NWC"3;
"S \NAC"
BN"52"28;
%"TAP"
"6","(-1850,4450)","2","mstr_standard","I54";
;
CDS_LIB"mstr_standard"
BODY_TYPE"PLUMBING"
HDL_TAP"TRUE";
"B \NAC \NWC"3;
"S \NAC"
BN"55"138;
%"TAP"
"6","(-1850,4350)","2","mstr_standard","I55";
;
CDS_LIB"mstr_standard"
BODY_TYPE"PLUMBING"
HDL_TAP"TRUE";
"B \NAC \NWC"3;
"S \NAC"
BN"53"137;
%"TAP"
"6","(-1850,4500)","2","mstr_standard","I56";
;
CDS_LIB"mstr_standard"
BODY_TYPE"PLUMBING"
HDL_TAP"TRUE";
"B \NAC \NWC"3;
"S \NAC"
BN"54"139;
%"TAP"
"6","(-1850,4550)","2","mstr_standard","I57";
;
CDS_LIB"mstr_standard"
BODY_TYPE"PLUMBING"
HDL_TAP"TRUE";
"B \NAC \NWC"3;
"S \NAC"
BN"57"140;
%"TAP"
"6","(-1850,4100)","2","mstr_standard","I58";
;
CDS_LIB"mstr_standard"
BODY_TYPE"PLUMBING"
HDL_TAP"TRUE";
"B \NAC \NWC"3;
"S \NAC"
BN"46"132;
%"TAP"
"6","(-1850,4150)","2","mstr_standard","I59";
;
CDS_LIB"mstr_standard"
BODY_TYPE"PLUMBING"
HDL_TAP"TRUE";
"B \NAC \NWC"3;
"S \NAC"
BN"49"133;
%"TAP"
"6","(850,4800)","2","mstr_standard","I6";
;
CDS_LIB"mstr_standard"
BODY_TYPE"PLUMBING"
HDL_TAP"TRUE";
"B \NAC \NWC"2;
"S \NAC"
BN"14"167;
%"TAP"
"6","(-1850,4050)","2","mstr_standard","I60";
;
CDS_LIB"mstr_standard"
BODY_TYPE"PLUMBING"
HDL_TAP"TRUE";
"B \NAC \NWC"3;
"S \NAC"
BN"47"104;
%"TAP"
"6","(-1850,4200)","2","mstr_standard","I61";
;
CDS_LIB"mstr_standard"
BODY_TYPE"PLUMBING"
HDL_TAP"TRUE";
"B \NAC \NWC"3;
"S \NAC"
BN"48"134;
%"TAP"
"6","(-1850,4250)","2","mstr_standard","I62";
;
CDS_LIB"mstr_standard"
BODY_TYPE"PLUMBING"
HDL_TAP"TRUE";
"B \NAC \NWC"3;
"S \NAC"
BN"51"135;
%"TAP"
"6","(-1850,4300)","2","mstr_standard","I63";
;
CDS_LIB"mstr_standard"
BODY_TYPE"PLUMBING"
HDL_TAP"TRUE";
"B \NAC \NWC"3;
"S \NAC"
BN"50"136;
%"SCONN288_H44441004"
"2","(-50,4300)","0","mstr_sconn","I64";
;
CDS_SEC"2"
LOCATION"J1G2"
PART_NUMBER"H44441-004"
MATERIAL"SCONN"
PACK_TYPE"PIP"
BOM_COST"MEM"
CDS_LIB"mstr_sconn"
SEC_TYPE"PIP"
SEC"2"
CDS_LOCATION"J1G2"
ROOM"DDR4_CH_H";
"DQS17P"
$PN"51"176;
"DQS9P"
$PN"7"156;
"DQS9N"
$PN"8"157;
"DQS8P"
$PN"197"158;
"DQS8N"
$PN"196"159;
"DQS7P"
$PN"278"160;
"DQS7N"
$PN"277"161;
"DQS6P"
$PN"267"143;
"DQS6N"
$PN"266"144;
"DQS5P"
$PN"256"145;
"DQS5N"
$PN"255"146;
"DQS4P"
$PN"245"147;
"DQS4N"
$PN"244"148;
"DQS3P"
$PN"186"149;
"DQS3N"
$PN"185"150;
"DQS2P"
$PN"175"151;
"DQS2N"
$PN"174"152;
"DQS1P"
$PN"164"24;
"DQS1N"
$PN"163"153;
"DQS17N"
$PN"52"162;
"DQS16P"
$PN"132"163;
"DQS16N"
$PN"133"164;
"DQS15P"
$PN"121"165;
"DQS15N"
$PN"122"27;
"DQS14P"
$PN"110"166;
"DQS14N"
$PN"111"167;
"DQS13P"
$PN"99"168;
"DQS13N"
$PN"100"169;
"DQS12P"
$PN"40"170;
"DQS12N"
$PN"41"171;
"DQS11P"
$PN"29"172;
"DQS11N"
$PN"30"173;
"DQS10P"
$PN"18"174;
"DQS10N"
$PN"19"175;
"DQS0P"
$PN"153"154;
"DQS0N"
$PN"152"155;
%"TAP"
"6","(-1850,3900)","2","mstr_standard","I65";
;
CDS_LIB"mstr_standard"
BODY_TYPE"PLUMBING"
HDL_TAP"TRUE";
"B \NAC \NWC"3;
"S \NAC"
BN"42"101;
%"TAP"
"6","(-1850,3850)","2","mstr_standard","I66";
;
CDS_LIB"mstr_standard"
BODY_TYPE"PLUMBING"
HDL_TAP"TRUE";
"B \NAC \NWC"3;
"S \NAC"
BN"43"100;
%"TAP"
"6","(-1850,3800)","2","mstr_standard","I67";
;
CDS_LIB"mstr_standard"
BODY_TYPE"PLUMBING"
HDL_TAP"TRUE";
"B \NAC \NWC"3;
"S \NAC"
BN"40"99;
%"TAP"
"6","(-1850,3950)","2","mstr_standard","I68";
;
CDS_LIB"mstr_standard"
BODY_TYPE"PLUMBING"
HDL_TAP"TRUE";
"B \NAC \NWC"3;
"S \NAC"
BN"45"102;
%"TAP"
"6","(-1850,4000)","2","mstr_standard","I69";
;
CDS_LIB"mstr_standard"
BODY_TYPE"PLUMBING"
HDL_TAP"TRUE";
"B \NAC \NWC"3;
"S \NAC"
BN"44"103;
%"TAP"
"6","(850,4700)","2","mstr_standard","I7";
;
CDS_LIB"mstr_standard"
BODY_TYPE"PLUMBING"
HDL_TAP"TRUE";
"B \NAC \NWC"2;
"S \NAC"
BN"13"169;
%"TAP"
"6","(-1850,3650)","2","mstr_standard","I70";
;
CDS_LIB"mstr_standard"
BODY_TYPE"PLUMBING"
HDL_TAP"TRUE";
"B \NAC \NWC"3;
"S \NAC"
BN"39"73;
%"TAP"
"6","(-1850,3600)","2","mstr_standard","I71";
;
CDS_LIB"mstr_standard"
BODY_TYPE"PLUMBING"
HDL_TAP"TRUE";
"B \NAC \NWC"3;
"S \NAC"
BN"36"96;
%"TAP"
"6","(-1850,3550)","2","mstr_standard","I72";
;
CDS_LIB"mstr_standard"
BODY_TYPE"PLUMBING"
HDL_TAP"TRUE";
"B \NAC \NWC"3;
"S \NAC"
BN"37"74;
%"TAP"
"6","(-1850,3750)","2","mstr_standard","I73";
;
CDS_LIB"mstr_standard"
BODY_TYPE"PLUMBING"
HDL_TAP"TRUE";
"B \NAC \NWC"3;
"S \NAC"
BN"41"98;
%"TAP"
"6","(-1850,3700)","2","mstr_standard","I74";
;
CDS_LIB"mstr_standard"
BODY_TYPE"PLUMBING"
HDL_TAP"TRUE";
"B \NAC \NWC"3;
"S \NAC"
BN"38"97;
%"TAP"
"6","(-1850,3400)","2","mstr_standard","I75";
;
CDS_LIB"mstr_standard"
BODY_TYPE"PLUMBING"
HDL_TAP"TRUE";
"B \NAC \NWC"3;
"S \NAC"
BN"32"26;
%"TAP"
"6","(-1850,3350)","2","mstr_standard","I76";
;
CDS_LIB"mstr_standard"
BODY_TYPE"PLUMBING"
HDL_TAP"TRUE";
"B \NAC \NWC"3;
"S \NAC"
BN"33"94;
%"TAP"
"6","(-1850,3300)","2","mstr_standard","I77";
;
CDS_LIB"mstr_standard"
BODY_TYPE"PLUMBING"
HDL_TAP"TRUE";
"B \NAC \NWC"3;
"S \NAC"
BN"30"93;
%"TAP"
"6","(-1850,3500)","2","mstr_standard","I78";
;
CDS_LIB"mstr_standard"
BODY_TYPE"PLUMBING"
HDL_TAP"TRUE";
"B \NAC \NWC"3;
"S \NAC"
BN"34"75;
%"TAP"
"6","(-1850,3450)","2","mstr_standard","I79";
;
CDS_LIB"mstr_standard"
BODY_TYPE"PLUMBING"
HDL_TAP"TRUE";
"B \NAC \NWC"3;
"S \NAC"
BN"35"95;
%"TAP"
"6","(650,5050)","2","mstr_standard","I8";
;
CDS_LIB"mstr_standard"
BODY_TYPE"PLUMBING"
HDL_TAP"TRUE";
"B \NAC \NWC"1;
"S \NAC"
BN"16"163;
%"TAP"
"6","(-1850,3100)","2","mstr_standard","I80";
;
CDS_LIB"mstr_standard"
BODY_TYPE"PLUMBING"
HDL_TAP"TRUE";
"B \NAC \NWC"3;
"S \NAC"
BN"26"72;
%"TAP"
"6","(-1850,3150)","2","mstr_standard","I81";
;
CDS_LIB"mstr_standard"
BODY_TYPE"PLUMBING"
HDL_TAP"TRUE";
"B \NAC \NWC"3;
"S \NAC"
BN"29"105;
%"TAP"
"6","(-1850,3050)","2","mstr_standard","I82";
;
CDS_LIB"mstr_standard"
BODY_TYPE"PLUMBING"
HDL_TAP"TRUE";
"B \NAC \NWC"3;
"S \NAC"
BN"27"71;
%"TAP"
"6","(-1850,3200)","2","mstr_standard","I83";
;
CDS_LIB"mstr_standard"
BODY_TYPE"PLUMBING"
HDL_TAP"TRUE";
"B \NAC \NWC"3;
"S \NAC"
BN"28"106;
%"TAP"
"6","(-1850,3250)","2","mstr_standard","I84";
;
CDS_LIB"mstr_standard"
BODY_TYPE"PLUMBING"
HDL_TAP"TRUE";
"B \NAC \NWC"3;
"S \NAC"
BN"31"92;
%"TAP"
"6","(-1850,2850)","2","mstr_standard","I85";
;
CDS_LIB"mstr_standard"
BODY_TYPE"PLUMBING"
HDL_TAP"TRUE";
"B \NAC \NWC"3;
"S \NAC"
BN"23"88;
%"TAP"
"6","(-1850,2900)","2","mstr_standard","I86";
;
CDS_LIB"mstr_standard"
BODY_TYPE"PLUMBING"
HDL_TAP"TRUE";
"B \NAC \NWC"3;
"S \NAC"
BN"22"89;
%"TAP"
"6","(-1850,2800)","2","mstr_standard","I87";
;
CDS_LIB"mstr_standard"
BODY_TYPE"PLUMBING"
HDL_TAP"TRUE";
"B \NAC \NWC"3;
"S \NAC"
BN"20"87;
%"TAP"
"6","(-1850,3000)","2","mstr_standard","I88";
;
CDS_LIB"mstr_standard"
BODY_TYPE"PLUMBING"
HDL_TAP"TRUE";
"B \NAC \NWC"3;
"S \NAC"
BN"24"91;
%"TAP"
"6","(-1850,2950)","2","mstr_standard","I89";
;
CDS_LIB"mstr_standard"
BODY_TYPE"PLUMBING"
HDL_TAP"TRUE";
"B \NAC \NWC"3;
"S \NAC"
BN"25"90;
%"TAP"
"6","(650,5150)","2","mstr_standard","I9";
;
CDS_LIB"mstr_standard"
BODY_TYPE"PLUMBING"
HDL_TAP"TRUE";
"B \NAC \NWC"1;
"S \NAC"
BN"17"176;
%"TAP"
"6","(-1850,2550)","2","mstr_standard","I90";
;
CDS_LIB"mstr_standard"
BODY_TYPE"PLUMBING"
HDL_TAP"TRUE";
"B \NAC \NWC"3;
"S \NAC"
BN"17"84;
%"TAP"
"6","(-1850,2600)","2","mstr_standard","I91";
;
CDS_LIB"mstr_standard"
BODY_TYPE"PLUMBING"
HDL_TAP"TRUE";
"B \NAC \NWC"3;
"S \NAC"
BN"16"69;
%"TAP"
"6","(-1850,2650)","2","mstr_standard","I92";
;
CDS_LIB"mstr_standard"
BODY_TYPE"PLUMBING"
HDL_TAP"TRUE";
"B \NAC \NWC"3;
"S \NAC"
BN"19"85;
%"TAP"
"6","(-1850,2700)","2","mstr_standard","I93";
;
CDS_LIB"mstr_standard"
BODY_TYPE"PLUMBING"
HDL_TAP"TRUE";
"B \NAC \NWC"3;
"S \NAC"
BN"18"111;
%"TAP"
"6","(-1850,2750)","2","mstr_standard","I94";
;
CDS_LIB"mstr_standard"
BODY_TYPE"PLUMBING"
HDL_TAP"TRUE";
"B \NAC \NWC"3;
"S \NAC"
BN"21"86;
%"TAP"
"6","(-1850,2300)","2","mstr_standard","I95";
;
CDS_LIB"mstr_standard"
BODY_TYPE"PLUMBING"
HDL_TAP"TRUE";
"B \NAC \NWC"3;
"S \NAC"
BN"10"80;
%"TAP"
"6","(-1850,2400)","2","mstr_standard","I96";
;
CDS_LIB"mstr_standard"
BODY_TYPE"PLUMBING"
HDL_TAP"TRUE";
"B \NAC \NWC"3;
"S \NAC"
BN"12"82;
%"TAP"
"6","(-1850,2350)","2","mstr_standard","I97";
;
CDS_LIB"mstr_standard"
BODY_TYPE"PLUMBING"
HDL_TAP"TRUE";
"B \NAC \NWC"3;
"S \NAC"
BN"13"81;
%"TAP"
"6","(-1850,2450)","2","mstr_standard","I98";
;
CDS_LIB"mstr_standard"
BODY_TYPE"PLUMBING"
HDL_TAP"TRUE";
"B \NAC \NWC"3;
"S \NAC"
BN"15"83;
%"TAP"
"6","(-1850,2500)","2","mstr_standard","I99";
;
CDS_LIB"mstr_standard"
BODY_TYPE"PLUMBING"
HDL_TAP"TRUE";
"B \NAC \NWC"3;
"S \NAC"
BN"14"70;
END.
